(kicad_pcb
	(version 20260206)
	(generator "pcbnew")
	(generator_version "10.0")
	(general
		(thickness 1.6)
		(legacy_teardrops no)
	)
	(paper "A4")
	(title_block
		(title "03242023_DA0F0TMBIJ0_F0T_Motherboard_J_brd_V01_OCP.brd")
		(comment 1 "Grand Teton / footprints 4065-4070 of 6105")
	)
	(layers
		(0 "F.Cu" signal "TOP")
		(4 "In1.Cu" signal "GND")
		(6 "In2.Cu" signal "IN1")
		(8 "In3.Cu" signal "GND1")
		(10 "In4.Cu" signal "IN2")
		(12 "In5.Cu" signal "GND2")
		(14 "In6.Cu" signal "IN3")
		(16 "In7.Cu" signal "GND3")
		(18 "In8.Cu" signal "VCC")
		(20 "In9.Cu" signal "VCC1")
		(22 "In10.Cu" signal "GND4")
		(24 "In11.Cu" signal "IN4")
		(26 "In12.Cu" signal "GND5")
		(28 "In13.Cu" signal "IN5")
		(30 "In14.Cu" signal "GND6")
		(32 "In15.Cu" signal "IN6")
		(34 "In16.Cu" signal "GND7")
		(2 "B.Cu" signal "BOTTOM")
		(9 "F.Adhes" user "F.Adhesive")
		(11 "B.Adhes" user "B.Adhesive")
		(13 "F.Paste" user "Package Geometry/Pastemask Top")
		(15 "B.Paste" user "Package Geometry/Pastemask Bottom")
		(5 "F.SilkS" user "Ref Des/Silkscreen Top")
		(7 "B.SilkS" user "Ref Des/Silkscreen Bottom")
		(1 "F.Mask" user "Board Geometry/Soldermask Top")
		(3 "B.Mask" user "Board Geometry/Soldermask Bottom")
		(17 "Dwgs.User" user "User.Drawings")
		(19 "Cmts.User" user "User.Comments")
		(21 "Eco1.User" user "User.Eco1")
		(23 "Eco2.User" user "User.Eco2")
		(25 "Edge.Cuts" user "Board Geometry/Outline")
		(27 "Margin" user)
		(31 "F.CrtYd" user "Package Geometry/Place Bound Top")
		(29 "B.CrtYd" user "Package Geometry/Place Bound Bottom")
		(35 "F.Fab" user "Ref Des/Assembly Top")
		(33 "B.Fab" user "Ref Des/Assembly Bottom")
	)
	(footprint ""
		(layer "F.Cu")
		(at 430.355756 -109.25937 -90)
		(property "Reference" "PC2093"
			(at 0 0 270)
			(layer "F.SilkS")
			(hide yes)
			(effects
				(font
					(size 1.27 1.27)
				)
			)
		)
		(property "Value" ""
			(at 0 0 270)
			(layer "F.Fab")
			(effects
				(font
					(size 1.27 1.27)
				)
			)
		)
		(duplicate_pad_numbers_are_jumpers no)
		(fp_line
			(start -0.7874 0.4064)
			(end -0.7874 -0.4064)
			(stroke
				(width 0.1524)
				(type default)
			)
			(layer "F.SilkS")
		)
		(fp_line
			(start 0.7874 0.4064)
			(end -0.7874 0.4064)
			(stroke
				(width 0.1524)
				(type default)
			)
			(layer "F.SilkS")
		)
		(fp_line
			(start -0.7874 -0.4064)
			(end 0.7874 -0.4064)
			(stroke
				(width 0.1524)
				(type default)
			)
			(layer "F.SilkS")
		)
		(fp_line
			(start 0.7874 -0.4064)
			(end 0.7874 0.4064)
			(stroke
				(width 0.1524)
				(type default)
			)
			(layer "F.SilkS")
		)
		(fp_line
			(start -0.67945 0.3048)
			(end -0.67945 -0.305054)
			(stroke
				(width 0.1)
				(type default)
			)
			(layer "F.Fab")
		)
		(fp_line
			(start -0.12065 0.3048)
			(end -0.67945 0.3048)
			(stroke
				(width 0.1)
				(type default)
			)
			(layer "F.Fab")
		)
		(fp_line
			(start 0.120396 0.3048)
			(end 0.120396 0.2794)
			(stroke
				(width 0.1)
				(type default)
			)
			(layer "F.Fab")
		)
		(fp_line
			(start 0.67945 0.3048)
			(end 0.120396 0.3048)
			(stroke
				(width 0.1)
				(type default)
			)
			(layer "F.Fab")
		)
		(fp_line
			(start -0.12065 0.2794)
			(end -0.12065 0.3048)
			(stroke
				(width 0.1)
				(type default)
			)
			(layer "F.Fab")
		)
		(fp_line
			(start 0.120396 0.2794)
			(end -0.12065 0.2794)
			(stroke
				(width 0.1)
				(type default)
			)
			(layer "F.Fab")
		)
		(fp_line
			(start -0.12065 -0.2794)
			(end 0.12065 -0.2794)
			(stroke
				(width 0.1)
				(type default)
			)
			(layer "F.Fab")
		)
		(fp_line
			(start 0.12065 -0.2794)
			(end 0.12065 -0.3048)
			(stroke
				(width 0.1)
				(type default)
			)
			(layer "F.Fab")
		)
		(fp_line
			(start 0.12065 -0.3048)
			(end 0.67945 -0.3048)
			(stroke
				(width 0.1)
				(type default)
			)
			(layer "F.Fab")
		)
		(fp_line
			(start 0.67945 -0.3048)
			(end 0.67945 0.3048)
			(stroke
				(width 0.1)
				(type default)
			)
			(layer "F.Fab")
		)
		(fp_line
			(start -0.67945 -0.305054)
			(end -0.12065 -0.305054)
			(stroke
				(width 0.1)
				(type default)
			)
			(layer "F.Fab")
		)
		(fp_line
			(start -0.12065 -0.305054)
			(end -0.12065 -0.2794)
			(stroke
				(width 0.1)
				(type default)
			)
			(layer "F.Fab")
		)
		(pad "1" smd circle
			(at -0.40005 0 270)
			(size 0 0)
			(layers "F.Cu" "F.Mask" "F.Paste")
			(net "GND")
		)
		(pad "2" smd circle
			(at 0.40005 0 270)
			(size 0 0)
			(layers "F.Cu" "F.Mask" "F.Paste")
			(net "P3V3_OCP_REG_1")
		)
	)
	(footprint ""
		(layer "F.Cu")
		(at 96.57588 -56.225948 180)
		(property "Reference" "R3027"
			(at 0 0 180)
			(layer "F.SilkS")
			(hide yes)
			(effects
				(font
					(size 1.27 1.27)
				)
			)
		)
		(property "Value" ""
			(at 0 0 180)
			(layer "F.Fab")
			(effects
				(font
					(size 1.27 1.27)
				)
			)
		)
		(duplicate_pad_numbers_are_jumpers no)
		(fp_line
			(start 0.7874 0.4064)
			(end -0.7874 0.4064)
			(stroke
				(width 0.1524)
				(type default)
			)
			(layer "F.SilkS")
		)
		(fp_line
			(start 0.7874 -0.4064)
			(end 0.7874 0.4064)
			(stroke
				(width 0.1524)
				(type default)
			)
			(layer "F.SilkS")
		)
		(fp_line
			(start -0.7874 0.4064)
			(end -0.7874 -0.4064)
			(stroke
				(width 0.1524)
				(type default)
			)
			(layer "F.SilkS")
		)
		(fp_line
			(start -0.7874 -0.4064)
			(end 0.7874 -0.4064)
			(stroke
				(width 0.1524)
				(type default)
			)
			(layer "F.SilkS")
		)
		(fp_line
			(start 0.67945 0.3048)
			(end 0.120396 0.3048)
			(stroke
				(width 0.1)
				(type default)
			)
			(layer "F.Fab")
		)
		(fp_line
			(start 0.67945 -0.3048)
			(end 0.67945 0.3048)
			(stroke
				(width 0.1)
				(type default)
			)
			(layer "F.Fab")
		)
		(fp_line
			(start 0.12065 -0.2794)
			(end 0.12065 -0.3048)
			(stroke
				(width 0.1)
				(type default)
			)
			(layer "F.Fab")
		)
		(fp_line
			(start 0.12065 -0.3048)
			(end 0.67945 -0.3048)
			(stroke
				(width 0.1)
				(type default)
			)
			(layer "F.Fab")
		)
		(fp_line
			(start 0.120396 0.3048)
			(end 0.120396 0.2794)
			(stroke
				(width 0.1)
				(type default)
			)
			(layer "F.Fab")
		)
		(fp_line
			(start 0.120396 0.2794)
			(end -0.12065 0.2794)
			(stroke
				(width 0.1)
				(type default)
			)
			(layer "F.Fab")
		)
		(fp_line
			(start -0.12065 0.3048)
			(end -0.67945 0.3048)
			(stroke
				(width 0.1)
				(type default)
			)
			(layer "F.Fab")
		)
		(fp_line
			(start -0.12065 0.2794)
			(end -0.12065 0.3048)
			(stroke
				(width 0.1)
				(type default)
			)
			(layer "F.Fab")
		)
		(fp_line
			(start -0.12065 -0.2794)
			(end 0.12065 -0.2794)
			(stroke
				(width 0.1)
				(type default)
			)
			(layer "F.Fab")
		)
		(fp_line
			(start -0.12065 -0.305054)
			(end -0.12065 -0.2794)
			(stroke
				(width 0.1)
				(type default)
			)
			(layer "F.Fab")
		)
		(fp_line
			(start -0.67945 0.3048)
			(end -0.67945 -0.305054)
			(stroke
				(width 0.1)
				(type default)
			)
			(layer "F.Fab")
		)
		(fp_line
			(start -0.67945 -0.305054)
			(end -0.12065 -0.305054)
			(stroke
				(width 0.1)
				(type default)
			)
			(layer "F.Fab")
		)
		(pad "1" smd circle
			(at -0.40005 0 180)
			(size 0 0)
			(layers "F.Cu" "F.Mask" "F.Paste")
			(net "JTAG_BMC_CPU_TCK")
		)
		(pad "2" smd circle
			(at 0.40005 0 180)
			(size 0 0)
			(layers "F.Cu" "F.Mask" "F.Paste")
			(net "GND")
		)
	)
	(footprint ""
		(layer "F.Cu")
		(at 77.8764 -37.262308 180)
		(property "Reference" "C1819"
			(at 0 0 180)
			(layer "F.SilkS")
			(hide yes)
			(effects
				(font
					(size 1.27 1.27)
				)
			)
		)
		(property "Value" ""
			(at 0 0 180)
			(layer "F.Fab")
			(effects
				(font
					(size 1.27 1.27)
				)
			)
		)
		(duplicate_pad_numbers_are_jumpers no)
		(fp_line
			(start 0.7874 0.4064)
			(end -0.7874 0.4064)
			(stroke
				(width 0.1524)
				(type default)
			)
			(layer "F.SilkS")
		)
		(fp_line
			(start 0.7874 -0.4064)
			(end 0.7874 0.4064)
			(stroke
				(width 0.1524)
				(type default)
			)
			(layer "F.SilkS")
		)
		(fp_line
			(start -0.7874 0.4064)
			(end -0.7874 -0.4064)
			(stroke
				(width 0.1524)
				(type default)
			)
			(layer "F.SilkS")
		)
		(fp_line
			(start -0.7874 -0.4064)
			(end 0.7874 -0.4064)
			(stroke
				(width 0.1524)
				(type default)
			)
			(layer "F.SilkS")
		)
		(fp_line
			(start 0.67945 0.3048)
			(end 0.120396 0.3048)
			(stroke
				(width 0.1)
				(type default)
			)
			(layer "F.Fab")
		)
		(fp_line
			(start 0.67945 -0.3048)
			(end 0.67945 0.3048)
			(stroke
				(width 0.1)
				(type default)
			)
			(layer "F.Fab")
		)
		(fp_line
			(start 0.12065 -0.2794)
			(end 0.12065 -0.3048)
			(stroke
				(width 0.1)
				(type default)
			)
			(layer "F.Fab")
		)
		(fp_line
			(start 0.12065 -0.3048)
			(end 0.67945 -0.3048)
			(stroke
				(width 0.1)
				(type default)
			)
			(layer "F.Fab")
		)
		(fp_line
			(start 0.120396 0.3048)
			(end 0.120396 0.2794)
			(stroke
				(width 0.1)
				(type default)
			)
			(layer "F.Fab")
		)
		(fp_line
			(start 0.120396 0.2794)
			(end -0.12065 0.2794)
			(stroke
				(width 0.1)
				(type default)
			)
			(layer "F.Fab")
		)
		(fp_line
			(start -0.12065 0.3048)
			(end -0.67945 0.3048)
			(stroke
				(width 0.1)
				(type default)
			)
			(layer "F.Fab")
		)
		(fp_line
			(start -0.12065 0.2794)
			(end -0.12065 0.3048)
			(stroke
				(width 0.1)
				(type default)
			)
			(layer "F.Fab")
		)
		(fp_line
			(start -0.12065 -0.2794)
			(end 0.12065 -0.2794)
			(stroke
				(width 0.1)
				(type default)
			)
			(layer "F.Fab")
		)
		(fp_line
			(start -0.12065 -0.305054)
			(end -0.12065 -0.2794)
			(stroke
				(width 0.1)
				(type default)
			)
			(layer "F.Fab")
		)
		(fp_line
			(start -0.67945 0.3048)
			(end -0.67945 -0.305054)
			(stroke
				(width 0.1)
				(type default)
			)
			(layer "F.Fab")
		)
		(fp_line
			(start -0.67945 -0.305054)
			(end -0.12065 -0.305054)
			(stroke
				(width 0.1)
				(type default)
			)
			(layer "F.Fab")
		)
		(pad "1" smd circle
			(at -0.40005 0 180)
			(size 0 0)
			(layers "F.Cu" "F.Mask" "F.Paste")
			(net "P3V3_OCP_V3_2")
		)
		(pad "2" smd circle
			(at 0.40005 0 180)
			(size 0 0)
			(layers "F.Cu" "F.Mask" "F.Paste")
			(net "GND")
		)
	)
	(footprint ""
		(layer "F.Cu")
		(at 382.165352 -342.726264 -90)
		(property "Reference" "PC228_P0_8"
			(at 0 0 270)
			(layer "F.SilkS")
			(hide yes)
			(effects
				(font
					(size 1.27 1.27)
				)
			)
		)
		(property "Value" ""
			(at 0 0 270)
			(layer "F.Fab")
			(effects
				(font
					(size 1.27 1.27)
				)
			)
		)
		(duplicate_pad_numbers_are_jumpers no)
		(fp_line
			(start -0.7874 0.4064)
			(end -0.7874 -0.4064)
			(stroke
				(width 0.1524)
				(type default)
			)
			(layer "F.SilkS")
		)
		(fp_line
			(start 0.7874 0.4064)
			(end -0.7874 0.4064)
			(stroke
				(width 0.1524)
				(type default)
			)
			(layer "F.SilkS")
		)
		(fp_line
			(start -0.7874 -0.4064)
			(end 0.7874 -0.4064)
			(stroke
				(width 0.1524)
				(type default)
			)
			(layer "F.SilkS")
		)
		(fp_line
			(start 0.7874 -0.4064)
			(end 0.7874 0.4064)
			(stroke
				(width 0.1524)
				(type default)
			)
			(layer "F.SilkS")
		)
		(fp_line
			(start -0.67945 0.3048)
			(end -0.67945 -0.305054)
			(stroke
				(width 0.1)
				(type default)
			)
			(layer "F.Fab")
		)
		(fp_line
			(start -0.12065 0.3048)
			(end -0.67945 0.3048)
			(stroke
				(width 0.1)
				(type default)
			)
			(layer "F.Fab")
		)
		(fp_line
			(start 0.120396 0.3048)
			(end 0.120396 0.2794)
			(stroke
				(width 0.1)
				(type default)
			)
			(layer "F.Fab")
		)
		(fp_line
			(start 0.67945 0.3048)
			(end 0.120396 0.3048)
			(stroke
				(width 0.1)
				(type default)
			)
			(layer "F.Fab")
		)
		(fp_line
			(start -0.12065 0.2794)
			(end -0.12065 0.3048)
			(stroke
				(width 0.1)
				(type default)
			)
			(layer "F.Fab")
		)
		(fp_line
			(start 0.120396 0.2794)
			(end -0.12065 0.2794)
			(stroke
				(width 0.1)
				(type default)
			)
			(layer "F.Fab")
		)
		(fp_line
			(start -0.12065 -0.2794)
			(end 0.12065 -0.2794)
			(stroke
				(width 0.1)
				(type default)
			)
			(layer "F.Fab")
		)
		(fp_line
			(start 0.12065 -0.2794)
			(end 0.12065 -0.3048)
			(stroke
				(width 0.1)
				(type default)
			)
			(layer "F.Fab")
		)
		(fp_line
			(start 0.12065 -0.3048)
			(end 0.67945 -0.3048)
			(stroke
				(width 0.1)
				(type default)
			)
			(layer "F.Fab")
		)
		(fp_line
			(start 0.67945 -0.3048)
			(end 0.67945 0.3048)
			(stroke
				(width 0.1)
				(type default)
			)
			(layer "F.Fab")
		)
		(fp_line
			(start -0.67945 -0.305054)
			(end -0.12065 -0.305054)
			(stroke
				(width 0.1)
				(type default)
			)
			(layer "F.Fab")
		)
		(fp_line
			(start -0.12065 -0.305054)
			(end -0.12065 -0.2794)
			(stroke
				(width 0.1)
				(type default)
			)
			(layer "F.Fab")
		)
		(pad "1" smd circle
			(at -0.40005 0 270)
			(size 0 0)
			(layers "F.Cu" "F.Mask" "F.Paste")
			(net "PVCCIN_CPU0_PVCC")
		)
		(pad "2" smd circle
			(at 0.40005 0 270)
			(size 0 0)
			(layers "F.Cu" "F.Mask" "F.Paste")
			(net "GND")
		)
	)
	(footprint ""
		(layer "F.Cu")
		(at 349.0849 -62.398148)
		(property "Reference" "C141"
			(at 0 0 0)
			(layer "F.SilkS")
			(hide yes)
			(effects
				(font
					(size 1.27 1.27)
				)
			)
		)
		(property "Value" ""
			(at 0 0 0)
			(layer "F.Fab")
			(effects
				(font
					(size 1.27 1.27)
				)
			)
		)
		(duplicate_pad_numbers_are_jumpers no)
		(fp_line
			(start -0.299974 -0.150114)
			(end 0.299974 -0.150114)
			(stroke
				(width 0.1)
				(type default)
			)
			(layer "F.Fab")
		)
		(fp_line
			(start -0.299974 0.150114)
			(end -0.299974 -0.150114)
			(stroke
				(width 0.1)
				(type default)
			)
			(layer "F.Fab")
		)
		(fp_line
			(start 0.299974 -0.150114)
			(end 0.299974 0.150114)
			(stroke
				(width 0.1)
				(type default)
			)
			(layer "F.Fab")
		)
		(fp_line
			(start 0.299974 0.150114)
			(end -0.299974 0.150114)
			(stroke
				(width 0.1)
				(type default)
			)
			(layer "F.Fab")
		)
		(pad "1" smd rect
			(at -0.2667 0)
			(size 0.3048 0.381)
			(layers "F.Cu" "F.Mask" "F.Paste")
			(net "DMI_CPU0_PCH_TX_C_DN<6>")
		)
		(pad "2" smd rect
			(at 0.2667 0)
			(size 0.3048 0.381)
			(layers "F.Cu" "F.Mask" "F.Paste")
			(net "DMI_CPU0_PCH_TX_DN<6>")
		)
		(zone
			(layer "In1.Cu")
			(hatch none 0.5)
			(connect_pads
				(clearance 0)
			)
			(min_thickness 0.25)
			(keepout
				(tracks not_allowed)
				(vias allowed)
				(pads allowed)
				(copperpour not_allowed)
				(footprints allowed)
			)
			(placement
				(enabled no)
				(sheetname "")
			)
			(fill
				(thermal_gap 0.5)
				(thermal_bridge_width 0.5)
				(island_removal_mode 0)
			)
			(polygon
				(pts
					(arc
						(start 348.6912 -62.156848)
						(mid 348.637318 -62.179166)
						(end 348.615 -62.233048)
					)
					(arc
						(start 348.615 -62.563248)
						(mid 348.637318 -62.61713)
						(end 348.6912 -62.639448)
					)
					(arc
						(start 348.9452 -62.639448)
						(mid 348.999082 -62.61713)
						(end 349.0214 -62.563248)
					)
					(arc
						(start 349.0214 -62.233048)
						(mid 348.999082 -62.179166)
						(end 348.9452 -62.156848)
					)
				)
			)
		)
		(zone
			(layer "In1.Cu")
			(hatch none 0.5)
			(connect_pads
				(clearance 0)
			)
			(min_thickness 0.25)
			(keepout
				(tracks not_allowed)
				(vias allowed)
				(pads allowed)
				(copperpour not_allowed)
				(footprints allowed)
			)
			(placement
				(enabled no)
				(sheetname "")
			)
			(fill
				(thermal_gap 0.5)
				(thermal_bridge_width 0.5)
				(island_removal_mode 0)
			)
			(polygon
				(pts
					(arc
						(start 349.2246 -62.156848)
						(mid 349.170718 -62.179166)
						(end 349.1484 -62.233048)
					)
					(arc
						(start 349.1484 -62.563248)
						(mid 349.170718 -62.61713)
						(end 349.2246 -62.639448)
					)
					(arc
						(start 349.4786 -62.639448)
						(mid 349.532482 -62.61713)
						(end 349.5548 -62.563248)
					)
					(arc
						(start 349.5548 -62.233048)
						(mid 349.532482 -62.179166)
						(end 349.4786 -62.156848)
					)
				)
			)
		)
	)
	(footprint ""
		(layer "F.Cu")
		(at 422.13403 -49.76749 180)
		(property "Reference" "R1706"
			(at 0 0 180)
			(layer "F.SilkS")
			(hide yes)
			(effects
				(font
					(size 1.27 1.27)
				)
			)
		)
		(property "Value" ""
			(at 0 0 180)
			(layer "F.Fab")
			(effects
				(font
					(size 1.27 1.27)
				)
			)
		)
		(duplicate_pad_numbers_are_jumpers no)
		(fp_line
			(start 0.7874 0.4064)
			(end -0.7874 0.4064)
			(stroke
				(width 0.1524)
				(type default)
			)
			(layer "F.SilkS")
		)
		(fp_line
			(start 0.7874 -0.4064)
			(end 0.7874 0.4064)
			(stroke
				(width 0.1524)
				(type default)
			)
			(layer "F.SilkS")
		)
		(fp_line
			(start -0.7874 0.4064)
			(end -0.7874 -0.4064)
			(stroke
				(width 0.1524)
				(type default)
			)
			(layer "F.SilkS")
		)
		(fp_line
			(start -0.7874 -0.4064)
			(end 0.7874 -0.4064)
			(stroke
				(width 0.1524)
				(type default)
			)
			(layer "F.SilkS")
		)
		(fp_line
			(start 0.67945 0.3048)
			(end 0.120396 0.3048)
			(stroke
				(width 0.1)
				(type default)
			)
			(layer "F.Fab")
		)
		(fp_line
			(start 0.67945 -0.3048)
			(end 0.67945 0.3048)
			(stroke
				(width 0.1)
				(type default)
			)
			(layer "F.Fab")
		)
		(fp_line
			(start 0.12065 -0.2794)
			(end 0.12065 -0.3048)
			(stroke
				(width 0.1)
				(type default)
			)
			(layer "F.Fab")
		)
		(fp_line
			(start 0.12065 -0.3048)
			(end 0.67945 -0.3048)
			(stroke
				(width 0.1)
				(type default)
			)
			(layer "F.Fab")
		)
		(fp_line
			(start 0.120396 0.3048)
			(end 0.120396 0.2794)
			(stroke
				(width 0.1)
				(type default)
			)
			(layer "F.Fab")
		)
		(fp_line
			(start 0.120396 0.2794)
			(end -0.12065 0.2794)
			(stroke
				(width 0.1)
				(type default)
			)
			(layer "F.Fab")
		)
		(fp_line
			(start -0.12065 0.3048)
			(end -0.67945 0.3048)
			(stroke
				(width 0.1)
				(type default)
			)
			(layer "F.Fab")
		)
		(fp_line
			(start -0.12065 0.2794)
			(end -0.12065 0.3048)
			(stroke
				(width 0.1)
				(type default)
			)
			(layer "F.Fab")
		)
		(fp_line
			(start -0.12065 -0.2794)
			(end 0.12065 -0.2794)
			(stroke
				(width 0.1)
				(type default)
			)
			(layer "F.Fab")
		)
		(fp_line
			(start -0.12065 -0.305054)
			(end -0.12065 -0.2794)
			(stroke
				(width 0.1)
				(type default)
			)
			(layer "F.Fab")
		)
		(fp_line
			(start -0.67945 0.3048)
			(end -0.67945 -0.305054)
			(stroke
				(width 0.1)
				(type default)
			)
			(layer "F.Fab")
		)
		(fp_line
			(start -0.67945 -0.305054)
			(end -0.12065 -0.305054)
			(stroke
				(width 0.1)
				(type default)
			)
			(layer "F.Fab")
		)
		(pad "1" smd circle
			(at -0.40005 0 180)
			(size 0 0)
			(layers "F.Cu" "F.Mask" "F.Paste")
			(net "P3V3")
		)
		(pad "2" smd circle
			(at 0.40005 0 180)
			(size 0 0)
			(layers "F.Cu" "F.Mask" "F.Paste")
			(net "PWRGD_P3V3_R1")
		)
	)
)
